(kicad_pcb
	(version 20260206)
	(generator "pcbnew")
	(generator_version "10.0")
	(general
		(thickness 1.6)
		(legacy_teardrops no)
	)
	(paper "A4")
	(title_block
		(title "peb — Lightning_PEB_BRD.brd")
		(comment 1 "Lightning (Wiwynn / Facebook NVMe JBOF) / footprints 1855-1862 of 2563")
	)
	(layers
		(0 "F.Cu" signal "TOP")
		(4 "In1.Cu" signal "L2GND")
		(6 "In2.Cu" signal "L3")
		(8 "In3.Cu" signal "L4VCC")
		(10 "In4.Cu" signal "L5VCC")
		(12 "In5.Cu" signal "L6")
		(14 "In6.Cu" signal "L7GND")
		(2 "B.Cu" signal "BOTTOM")
		(9 "F.Adhes" user "F.Adhesive")
		(11 "B.Adhes" user "B.Adhesive")
		(13 "F.Paste" user "Package Geometry/Pastemask Top")
		(15 "B.Paste" user "Package Geometry/Pastemask Bottom")
		(5 "F.SilkS" user "Ref Des/Silkscreen Top")
		(7 "B.SilkS" user "Ref Des/Silkscreen Bottom")
		(1 "F.Mask" user "Board Geometry/Soldermask Top")
		(3 "B.Mask" user "Board Geometry/Soldermask Bottom")
		(17 "Dwgs.User" user "User.Drawings")
		(19 "Cmts.User" user "User.Comments")
		(21 "Eco1.User" user "User.Eco1")
		(23 "Eco2.User" user "User.Eco2")
		(25 "Edge.Cuts" user "Board Geometry/Outline")
		(27 "Margin" user)
		(31 "F.CrtYd" user "Package Geometry/Place Bound Top")
		(29 "B.CrtYd" user "Package Geometry/Place Bound Bottom")
		(35 "F.Fab" user "Ref Des/Assembly Top")
		(33 "B.Fab" user "Ref Des/Assembly Bottom")
	)
	(footprint ""
		(layer "B.Cu")
		(at 249.8344 -35.0012 90)
		(property "Reference" "C487"
			(at 0 0 90)
			(layer "B.SilkS")
			(hide yes)
			(effects
				(font
					(size 1.27 1.27)
				)
				(justify mirror)
			)
		)
		(property "Value" "SCD1U16V1KX-1-GP"
			(at 2.8321 -1.7399 90)
			(unlocked yes)
			(layer "B.Fab")
			(hide yes)
			(effects
				(font
					(size 1.016 1.016)
					(thickness 0.1524)
				)
				(justify mirror)
			)
		)
		(property "Device Type" "C0201H13"
			(at 2.8321 -3.2639 90)
			(unlocked yes)
			(layer "B.Fab")
			(hide yes)
			(effects
				(font
					(size 1.016 1.016)
					(thickness 0.1524)
				)
				(justify mirror)
			)
		)
		(duplicate_pad_numbers_are_jumpers no)
		(fp_rect
			(start 0.2794 0.6477)
			(end -0.2794 -0.6477)
			(stroke
				(width 0)
				(type default)
			)
			(fill no)
			(layer "B.CrtYd")
		)
		(fp_rect
			(start 0.2794 0.6477)
			(end -0.2794 -0.6477)
			(stroke
				(width 0)
				(type default)
			)
			(fill no)
			(layer "B.Fab")
		)
		(pad "1" smd custom
			(at 0 -0.2794 270)
			(size 0.0762 0.0762)
			(layers "B.Cu" "B.Mask" "B.Paste")
			(net "DUT_VDDO")
			(options
				(clearance outline)
				(anchor circle)
			)
			(primitives
				(gr_poly
					(pts
						(arc
							(start 0.1524 0.127)
							(mid 0.137521 0.162921)
							(end 0.1016 0.1778)
						)
						(arc
							(start -0.1016 0.1778)
							(mid -0.137521 0.162921)
							(end -0.1524 0.127)
						)
						(arc
							(start -0.1524 -0.127)
							(mid -0.137521 -0.162921)
							(end -0.1016 -0.1778)
						)
						(arc
							(start 0.1016 -0.1778)
							(mid 0.137521 -0.162921)
							(end 0.1524 -0.127)
						)
					)
					(width 0)
					(fill yes)
				)
			)
		)
		(pad "2" smd custom
			(at 0 0.2794 270)
			(size 0.0762 0.0762)
			(layers "B.Cu" "B.Mask" "B.Paste")
			(net "GND")
			(options
				(clearance outline)
				(anchor circle)
			)
			(primitives
				(gr_poly
					(pts
						(arc
							(start 0.1524 0.127)
							(mid 0.137521 0.162921)
							(end 0.1016 0.1778)
						)
						(arc
							(start -0.1016 0.1778)
							(mid -0.137521 0.162921)
							(end -0.1524 0.127)
						)
						(arc
							(start -0.1524 -0.127)
							(mid -0.137521 -0.162921)
							(end -0.1016 -0.1778)
						)
						(arc
							(start 0.1016 -0.1778)
							(mid 0.137521 -0.162921)
							(end 0.1524 -0.127)
						)
					)
					(width 0)
					(fill yes)
				)
			)
		)
	)
	(footprint ""
		(layer "B.Cu")
		(at 243.586 -57.995058 90)
		(property "Reference" "C511"
			(at 0 0 90)
			(layer "B.SilkS")
			(hide yes)
			(effects
				(font
					(size 1.27 1.27)
				)
				(justify mirror)
			)
		)
		(property "Value" "SCD1U16V1KX-1-GP"
			(at 2.8321 -1.7399 90)
			(unlocked yes)
			(layer "B.Fab")
			(hide yes)
			(effects
				(font
					(size 1.016 1.016)
					(thickness 0.1524)
				)
				(justify mirror)
			)
		)
		(property "Device Type" "C0201H13"
			(at 2.8321 -3.2639 90)
			(unlocked yes)
			(layer "B.Fab")
			(hide yes)
			(effects
				(font
					(size 1.016 1.016)
					(thickness 0.1524)
				)
				(justify mirror)
			)
		)
		(duplicate_pad_numbers_are_jumpers no)
		(fp_rect
			(start 0.2794 0.6477)
			(end -0.2794 -0.6477)
			(stroke
				(width 0)
				(type default)
			)
			(fill no)
			(layer "B.CrtYd")
		)
		(fp_rect
			(start 0.2794 0.6477)
			(end -0.2794 -0.6477)
			(stroke
				(width 0)
				(type default)
			)
			(fill no)
			(layer "B.Fab")
		)
		(pad "1" smd custom
			(at 0 -0.2794 270)
			(size 0.0762 0.0762)
			(layers "B.Cu" "B.Mask" "B.Paste")
			(net "DUT_AVD_TX")
			(options
				(clearance outline)
				(anchor circle)
			)
			(primitives
				(gr_poly
					(pts
						(arc
							(start 0.1524 0.127)
							(mid 0.137521 0.162921)
							(end 0.1016 0.1778)
						)
						(arc
							(start -0.1016 0.1778)
							(mid -0.137521 0.162921)
							(end -0.1524 0.127)
						)
						(arc
							(start -0.1524 -0.127)
							(mid -0.137521 -0.162921)
							(end -0.1016 -0.1778)
						)
						(arc
							(start 0.1016 -0.1778)
							(mid 0.137521 -0.162921)
							(end 0.1524 -0.127)
						)
					)
					(width 0)
					(fill yes)
				)
			)
		)
		(pad "2" smd custom
			(at 0 0.2794 270)
			(size 0.0762 0.0762)
			(layers "B.Cu" "B.Mask" "B.Paste")
			(net "GND")
			(options
				(clearance outline)
				(anchor circle)
			)
			(primitives
				(gr_poly
					(pts
						(arc
							(start 0.1524 0.127)
							(mid 0.137521 0.162921)
							(end 0.1016 0.1778)
						)
						(arc
							(start -0.1016 0.1778)
							(mid -0.137521 0.162921)
							(end -0.1524 0.127)
						)
						(arc
							(start -0.1524 -0.127)
							(mid -0.137521 -0.162921)
							(end -0.1016 -0.1778)
						)
						(arc
							(start 0.1016 -0.1778)
							(mid 0.137521 -0.162921)
							(end 0.1524 -0.127)
						)
					)
					(width 0)
					(fill yes)
				)
			)
		)
	)
	(footprint ""
		(layer "B.Cu")
		(at 151.649176 -33.545272 180)
		(property "Reference" "C229"
			(at 0 0 0)
			(layer "B.SilkS")
			(hide yes)
			(effects
				(font
					(size 1.27 1.27)
				)
				(justify mirror)
			)
		)
		(property "Value" "SCD1U10V2KX-5GP"
			(at -1.1811 -2.7051 180)
			(unlocked yes)
			(layer "B.Fab")
			(hide yes)
			(effects
				(font
					(size 1.016 1.016)
					(thickness 0.1524)
				)
				(justify mirror)
			)
		)
		(property "Device Type" "C402H22"
			(at -1.1811 -4.2291 180)
			(unlocked yes)
			(layer "B.Fab")
			(hide yes)
			(effects
				(font
					(size 1.016 1.016)
					(thickness 0.1524)
				)
				(justify mirror)
			)
		)
		(duplicate_pad_numbers_are_jumpers no)
		(fp_rect
			(start 0.4318 0.9525)
			(end -0.4318 -0.9525)
			(stroke
				(width 0)
				(type default)
			)
			(fill no)
			(layer "B.CrtYd")
		)
		(fp_rect
			(start 0.4318 0.9525)
			(end -0.4318 -0.9525)
			(stroke
				(width 0)
				(type default)
			)
			(fill no)
			(layer "B.Fab")
		)
		(pad "1" smd custom
			(at 0 -0.4445)
			(size 0.1524 0.1524)
			(layers "B.Cu" "B.Mask" "B.Paste")
			(net "GND")
			(options
				(clearance outline)
				(anchor circle)
			)
			(primitives
				(gr_poly
					(pts
						(arc
							(start 0.3048 0.2032)
							(mid 0.275042 0.275042)
							(end 0.2032 0.3048)
						)
						(arc
							(start -0.2032 0.3048)
							(mid -0.275042 0.275042)
							(end -0.3048 0.2032)
						)
						(arc
							(start -0.3048 -0.2032)
							(mid -0.275042 -0.275042)
							(end -0.2032 -0.3048)
						)
						(arc
							(start 0.2032 -0.3048)
							(mid 0.275042 -0.275042)
							(end 0.3048 -0.2032)
						)
					)
					(width 0)
					(fill yes)
				)
			)
		)
		(pad "2" smd custom
			(at 0 0.4445)
			(size 0.1524 0.1524)
			(layers "B.Cu" "B.Mask" "B.Paste")
			(net "P3V3_STBY")
			(options
				(clearance outline)
				(anchor circle)
			)
			(primitives
				(gr_poly
					(pts
						(arc
							(start 0.3048 0.2032)
							(mid 0.275042 0.275042)
							(end 0.2032 0.3048)
						)
						(arc
							(start -0.2032 0.3048)
							(mid -0.275042 0.275042)
							(end -0.3048 0.2032)
						)
						(arc
							(start -0.3048 -0.2032)
							(mid -0.275042 -0.275042)
							(end -0.2032 -0.3048)
						)
						(arc
							(start 0.2032 -0.3048)
							(mid 0.275042 -0.275042)
							(end 0.3048 -0.2032)
						)
					)
					(width 0)
					(fill yes)
				)
			)
		)
	)
	(footprint ""
		(layer "B.Cu")
		(at 342.1126 -175.7426)
		(property "Reference" "R3245"
			(at 0 0 0)
			(layer "B.SilkS")
			(hide yes)
			(effects
				(font
					(size 1.27 1.27)
				)
				(justify mirror)
			)
		)
		(property "Value" "0R2J-2-GP"
			(at -0.064008 -3.993896 0)
			(unlocked yes)
			(layer "B.Fab")
			(hide yes)
			(effects
				(font
					(size 1.016 1.016)
					(thickness 0.1524)
				)
				(justify mirror)
			)
		)
		(property "Device Type" "R402H16"
			(at -0.064008 -5.517896 0)
			(unlocked yes)
			(layer "B.Fab")
			(hide yes)
			(effects
				(font
					(size 1.016 1.016)
					(thickness 0.1524)
				)
				(justify mirror)
			)
		)
		(duplicate_pad_numbers_are_jumpers no)
		(fp_line
			(start -0.508 -0.9398)
			(end 0.508 -0.9398)
			(stroke
				(width 0.1524)
				(type default)
			)
			(layer "B.SilkS")
		)
		(fp_line
			(start 0.508 -0.9398)
			(end 0.508 0.9398)
			(stroke
				(width 0.1524)
				(type default)
			)
			(layer "B.SilkS")
		)
		(fp_rect
			(start 0.508 0.9398)
			(end -0.508 -0.9398)
			(stroke
				(width 0)
				(type default)
			)
			(fill no)
			(layer "B.CrtYd")
		)
		(fp_rect
			(start 0.508 0.9398)
			(end -0.508 -0.9398)
			(stroke
				(width 0)
				(type default)
			)
			(fill no)
			(layer "B.Fab")
		)
		(pad "1" smd custom
			(at 0 -0.4445 180)
			(size 0.1397 0.1397)
			(layers "B.Cu" "B.Mask" "B.Paste")
			(net "SSD_PERST_Y14")
			(options
				(clearance outline)
				(anchor circle)
			)
			(primitives
				(gr_poly
					(pts
						(arc
							(start -0.1778 0.2794)
							(mid -0.249642 0.249642)
							(end -0.2794 0.1778)
						)
						(arc
							(start -0.2794 -0.1778)
							(mid -0.249642 -0.249642)
							(end -0.1778 -0.2794)
						)
						(arc
							(start 0.1778 -0.2794)
							(mid 0.249642 -0.249642)
							(end 0.2794 -0.1778)
						)
						(arc
							(start 0.2794 0.1778)
							(mid 0.249642 0.249642)
							(end 0.1778 0.2794)
						)
					)
					(width 0)
					(fill yes)
				)
			)
		)
		(pad "2" smd custom
			(at 0 0.4445 180)
			(size 0.1397 0.1397)
			(layers "B.Cu" "B.Mask" "B.Paste")
			(net "SSD_PERST#14_R")
			(options
				(clearance outline)
				(anchor circle)
			)
			(primitives
				(gr_poly
					(pts
						(arc
							(start -0.1778 0.2794)
							(mid -0.249642 0.249642)
							(end -0.2794 0.1778)
						)
						(arc
							(start -0.2794 -0.1778)
							(mid -0.249642 -0.249642)
							(end -0.1778 -0.2794)
						)
						(arc
							(start 0.1778 -0.2794)
							(mid 0.249642 -0.249642)
							(end 0.2794 -0.1778)
						)
						(arc
							(start 0.2794 0.1778)
							(mid 0.249642 0.249642)
							(end 0.1778 0.2794)
						)
					)
					(width 0)
					(fill yes)
				)
			)
		)
	)
	(footprint ""
		(layer "B.Cu")
		(at 37.1221 -114.55146 180)
		(property "Reference" "R464"
			(at 0 0 0)
			(layer "B.SilkS")
			(hide yes)
			(effects
				(font
					(size 1.27 1.27)
				)
				(justify mirror)
			)
		)
		(property "Value" "0R2J-2-GP"
			(at -0.064008 -3.993896 180)
			(unlocked yes)
			(layer "B.Fab")
			(hide yes)
			(effects
				(font
					(size 1.016 1.016)
					(thickness 0.1524)
				)
				(justify mirror)
			)
		)
		(property "Device Type" "R402H16"
			(at -0.064008 -5.517896 180)
			(unlocked yes)
			(layer "B.Fab")
			(hide yes)
			(effects
				(font
					(size 1.016 1.016)
					(thickness 0.1524)
				)
				(justify mirror)
			)
		)
		(duplicate_pad_numbers_are_jumpers no)
		(fp_line
			(start 0.508 -0.9398)
			(end 0.508 0.9398)
			(stroke
				(width 0.1524)
				(type default)
			)
			(layer "B.SilkS")
		)
		(fp_line
			(start -0.508 -0.9398)
			(end 0.508 -0.9398)
			(stroke
				(width 0.1524)
				(type default)
			)
			(layer "B.SilkS")
		)
		(fp_rect
			(start 0.508 0.9398)
			(end -0.508 -0.9398)
			(stroke
				(width 0)
				(type default)
			)
			(fill no)
			(layer "B.CrtYd")
		)
		(fp_rect
			(start 0.508 0.9398)
			(end -0.508 -0.9398)
			(stroke
				(width 0)
				(type default)
			)
			(fill no)
			(layer "B.Fab")
		)
		(pad "1" smd custom
			(at 0 -0.4445)
			(size 0.1397 0.1397)
			(layers "B.Cu" "B.Mask" "B.Paste")
			(net "GND")
			(options
				(clearance outline)
				(anchor circle)
			)
			(primitives
				(gr_poly
					(pts
						(arc
							(start -0.1778 0.2794)
							(mid -0.249642 0.249642)
							(end -0.2794 0.1778)
						)
						(arc
							(start -0.2794 -0.1778)
							(mid -0.249642 -0.249642)
							(end -0.1778 -0.2794)
						)
						(arc
							(start 0.1778 -0.2794)
							(mid 0.249642 -0.249642)
							(end 0.2794 -0.1778)
						)
						(arc
							(start 0.2794 0.1778)
							(mid 0.249642 0.249642)
							(end 0.1778 0.2794)
						)
					)
					(width 0)
					(fill yes)
				)
			)
		)
		(pad "2" smd custom
			(at 0 0.4445)
			(size 0.1397 0.1397)
			(layers "B.Cu" "B.Mask" "B.Paste")
			(net "RMII_BMC_PHY_TXD0")
			(options
				(clearance outline)
				(anchor circle)
			)
			(primitives
				(gr_poly
					(pts
						(arc
							(start -0.1778 0.2794)
							(mid -0.249642 0.249642)
							(end -0.2794 0.1778)
						)
						(arc
							(start -0.2794 -0.1778)
							(mid -0.249642 -0.249642)
							(end -0.1778 -0.2794)
						)
						(arc
							(start 0.1778 -0.2794)
							(mid 0.249642 -0.249642)
							(end 0.2794 -0.1778)
						)
						(arc
							(start 0.2794 0.1778)
							(mid 0.249642 0.249642)
							(end 0.1778 0.2794)
						)
					)
					(width 0)
					(fill yes)
				)
			)
		)
	)
	(footprint ""
		(layer "B.Cu")
		(at 42.129456 -135.618982)
		(property "Reference" "TP191"
			(at 0 0 0)
			(layer "B.SilkS")
			(hide yes)
			(effects
				(font
					(size 1.27 1.27)
				)
				(justify mirror)
			)
		)
		(property "Value" "TPAD28-2-GP"
			(at 0.0127 -1.6637 0)
			(unlocked yes)
			(layer "B.Fab")
			(hide yes)
			(effects
				(font
					(size 1.016 1.016)
					(thickness 0.1524)
				)
				(justify mirror)
			)
		)
		(property "Device Type" "TPAD28"
			(at 0.0127 -3.1877 0)
			(unlocked yes)
			(layer "B.Fab")
			(hide yes)
			(effects
				(font
					(size 1.016 1.016)
					(thickness 0.1524)
				)
				(justify mirror)
			)
		)
		(duplicate_pad_numbers_are_jumpers no)
		(fp_poly
			(pts
				(arc
					(start 0.3556 0)
					(mid -0.3556 0)
					(end 0.3556 0)
				)
			)
			(stroke
				(width 0)
				(type default)
			)
			(fill no)
			(layer "B.CrtYd")
		)
		(fp_poly
			(pts
				(arc
					(start 0.6096 0)
					(mid -0.6096 0)
					(end 0.6096 0)
				)
			)
			(stroke
				(width 0)
				(type default)
			)
			(fill no)
			(layer "B.Fab")
		)
		(pad "1" smd circle
			(at 0 0 180)
			(size 0.7112 0.7112)
			(layers "B.Cu" "B.Mask" "B.Paste")
			(net "TP_GPIOO7")
		)
	)
	(footprint ""
		(layer "B.Cu")
		(at 72.39 -190.627)
		(property "Reference" "R143"
			(at 0 0 0)
			(layer "B.SilkS")
			(hide yes)
			(effects
				(font
					(size 1.27 1.27)
				)
				(justify mirror)
			)
		)
		(property "Value" "4K7R2F-GP"
			(at -0.064008 -3.993896 0)
			(unlocked yes)
			(layer "B.Fab")
			(hide yes)
			(effects
				(font
					(size 1.016 1.016)
					(thickness 0.1524)
				)
				(justify mirror)
			)
		)
		(property "Device Type" "R402H16"
			(at -0.064008 -5.517896 0)
			(unlocked yes)
			(layer "B.Fab")
			(hide yes)
			(effects
				(font
					(size 1.016 1.016)
					(thickness 0.1524)
				)
				(justify mirror)
			)
		)
		(duplicate_pad_numbers_are_jumpers no)
		(fp_line
			(start -0.508 -0.9398)
			(end 0.508 -0.9398)
			(stroke
				(width 0.1524)
				(type default)
			)
			(layer "B.SilkS")
		)
		(fp_line
			(start 0.508 -0.9398)
			(end 0.508 0.9398)
			(stroke
				(width 0.1524)
				(type default)
			)
			(layer "B.SilkS")
		)
		(fp_rect
			(start 0.508 0.9398)
			(end -0.508 -0.9398)
			(stroke
				(width 0)
				(type default)
			)
			(fill no)
			(layer "B.CrtYd")
		)
		(fp_rect
			(start 0.508 0.9398)
			(end -0.508 -0.9398)
			(stroke
				(width 0)
				(type default)
			)
			(fill no)
			(layer "B.Fab")
		)
		(pad "1" smd custom
			(at 0 -0.4445 180)
			(size 0.1397 0.1397)
			(layers "B.Cu" "B.Mask" "B.Paste")
			(net "BMC_SSD_RST#0_A0")
			(options
				(clearance outline)
				(anchor circle)
			)
			(primitives
				(gr_poly
					(pts
						(arc
							(start -0.1778 0.2794)
							(mid -0.249642 0.249642)
							(end -0.2794 0.1778)
						)
						(arc
							(start -0.2794 -0.1778)
							(mid -0.249642 -0.249642)
							(end -0.1778 -0.2794)
						)
						(arc
							(start 0.1778 -0.2794)
							(mid 0.249642 -0.249642)
							(end 0.2794 -0.1778)
						)
						(arc
							(start 0.2794 0.1778)
							(mid 0.249642 0.249642)
							(end 0.1778 0.2794)
						)
					)
					(width 0)
					(fill yes)
				)
			)
		)
		(pad "2" smd custom
			(at 0 0.4445 180)
			(size 0.1397 0.1397)
			(layers "B.Cu" "B.Mask" "B.Paste")
			(net "P3V3_STBY")
			(options
				(clearance outline)
				(anchor circle)
			)
			(primitives
				(gr_poly
					(pts
						(arc
							(start -0.1778 0.2794)
							(mid -0.249642 0.249642)
							(end -0.2794 0.1778)
						)
						(arc
							(start -0.2794 -0.1778)
							(mid -0.249642 -0.249642)
							(end -0.1778 -0.2794)
						)
						(arc
							(start 0.1778 -0.2794)
							(mid 0.249642 -0.249642)
							(end 0.2794 -0.1778)
						)
						(arc
							(start 0.2794 0.1778)
							(mid 0.249642 0.249642)
							(end 0.1778 0.2794)
						)
					)
					(width 0)
					(fill yes)
				)
			)
		)
	)
	(footprint ""
		(layer "B.Cu")
		(at 131.5212 -196.3928)
		(property "Reference" "R4125"
			(at 0 0 0)
			(layer "B.SilkS")
			(hide yes)
			(effects
				(font
					(size 1.27 1.27)
				)
				(justify mirror)
			)
		)
		(property "Value" "4K7R2F-GP"
			(at -0.064008 -3.993896 0)
			(unlocked yes)
			(layer "B.Fab")
			(hide yes)
			(effects
				(font
					(size 1.016 1.016)
					(thickness 0.1524)
				)
				(justify mirror)
			)
		)
		(property "Device Type" "R402H16"
			(at -0.064008 -5.517896 0)
			(unlocked yes)
			(layer "B.Fab")
			(hide yes)
			(effects
				(font
					(size 1.016 1.016)
					(thickness 0.1524)
				)
				(justify mirror)
			)
		)
		(duplicate_pad_numbers_are_jumpers no)
		(fp_line
			(start -0.508 -0.9398)
			(end 0.508 -0.9398)
			(stroke
				(width 0.1524)
				(type default)
			)
			(layer "B.SilkS")
		)
		(fp_line
			(start 0.508 -0.9398)
			(end 0.508 0.9398)
			(stroke
				(width 0.1524)
				(type default)
			)
			(layer "B.SilkS")
		)
		(fp_rect
			(start 0.508 0.9398)
			(end -0.508 -0.9398)
			(stroke
				(width 0)
				(type default)
			)
			(fill no)
			(layer "B.CrtYd")
		)
		(fp_rect
			(start 0.508 0.9398)
			(end -0.508 -0.9398)
			(stroke
				(width 0)
				(type default)
			)
			(fill no)
			(layer "B.Fab")
		)
		(pad "1" smd custom
			(at 0 -0.4445 180)
			(size 0.1397 0.1397)
			(layers "B.Cu" "B.Mask" "B.Paste")
			(net "SSD_PRSNT#2")
			(options
				(clearance outline)
				(anchor circle)
			)
			(primitives
				(gr_poly
					(pts
						(arc
							(start -0.1778 0.2794)
							(mid -0.249642 0.249642)
							(end -0.2794 0.1778)
						)
						(arc
							(start -0.2794 -0.1778)
							(mid -0.249642 -0.249642)
							(end -0.1778 -0.2794)
						)
						(arc
							(start 0.1778 -0.2794)
							(mid 0.249642 -0.249642)
							(end 0.2794 -0.1778)
						)
						(arc
							(start 0.2794 0.1778)
							(mid 0.249642 0.249642)
							(end 0.1778 0.2794)
						)
					)
					(width 0)
					(fill yes)
				)
			)
		)
		(pad "2" smd custom
			(at 0 0.4445 180)
			(size 0.1397 0.1397)
			(layers "B.Cu" "B.Mask" "B.Paste")
			(net "P3V3_STBY")
			(options
				(clearance outline)
				(anchor circle)
			)
			(primitives
				(gr_poly
					(pts
						(arc
							(start -0.1778 0.2794)
							(mid -0.249642 0.249642)
							(end -0.2794 0.1778)
						)
						(arc
							(start -0.2794 -0.1778)
							(mid -0.249642 -0.249642)
							(end -0.1778 -0.2794)
						)
						(arc
							(start 0.1778 -0.2794)
							(mid 0.249642 -0.249642)
							(end 0.2794 -0.1778)
						)
						(arc
							(start 0.2794 0.1778)
							(mid 0.249642 0.249642)
							(end 0.1778 0.2794)
						)
					)
					(width 0)
					(fill yes)
				)
			)
		)
	)
)
